(kicad_pcb
	(version 20260206)
	(generator "pcbnew")
	(generator_version "10.0")
	(general
		(thickness 1.6)
		(legacy_teardrops no)
	)
	(paper "A4")
	(title_block
		(title "03242023_DA0F0TMBIJ0_F0T_Motherboard_J_brd_V01_OCP.brd")
		(comment 1 "Grand Teton / footprints 2816-2821 of 6105")
	)
	(layers
		(0 "F.Cu" signal "TOP")
		(4 "In1.Cu" signal "GND")
		(6 "In2.Cu" signal "IN1")
		(8 "In3.Cu" signal "GND1")
		(10 "In4.Cu" signal "IN2")
		(12 "In5.Cu" signal "GND2")
		(14 "In6.Cu" signal "IN3")
		(16 "In7.Cu" signal "GND3")
		(18 "In8.Cu" signal "VCC")
		(20 "In9.Cu" signal "VCC1")
		(22 "In10.Cu" signal "GND4")
		(24 "In11.Cu" signal "IN4")
		(26 "In12.Cu" signal "GND5")
		(28 "In13.Cu" signal "IN5")
		(30 "In14.Cu" signal "GND6")
		(32 "In15.Cu" signal "IN6")
		(34 "In16.Cu" signal "GND7")
		(2 "B.Cu" signal "BOTTOM")
		(9 "F.Adhes" user "F.Adhesive")
		(11 "B.Adhes" user "B.Adhesive")
		(13 "F.Paste" user "Package Geometry/Pastemask Top")
		(15 "B.Paste" user "Package Geometry/Pastemask Bottom")
		(5 "F.SilkS" user "Ref Des/Silkscreen Top")
		(7 "B.SilkS" user "Ref Des/Silkscreen Bottom")
		(1 "F.Mask" user "Board Geometry/Soldermask Top")
		(3 "B.Mask" user "Board Geometry/Soldermask Bottom")
		(17 "Dwgs.User" user "User.Drawings")
		(19 "Cmts.User" user "User.Comments")
		(21 "Eco1.User" user "User.Eco1")
		(23 "Eco2.User" user "User.Eco2")
		(25 "Edge.Cuts" user "Board Geometry/Outline")
		(27 "Margin" user)
		(31 "F.CrtYd" user "Package Geometry/Place Bound Top")
		(29 "B.CrtYd" user "Package Geometry/Place Bound Bottom")
		(35 "F.Fab" user "Ref Des/Assembly Top")
		(33 "B.Fab" user "Ref Des/Assembly Bottom")
	)
	(footprint ""
		(layer "F.Cu")
		(at 411.35681 -29.478986 -90)
		(property "Reference" "R1333"
			(at 0 0 270)
			(layer "F.SilkS")
			(hide yes)
			(effects
				(font
					(size 1.27 1.27)
				)
			)
		)
		(property "Value" ""
			(at 0 0 270)
			(layer "F.Fab")
			(effects
				(font
					(size 1.27 1.27)
				)
			)
		)
		(duplicate_pad_numbers_are_jumpers no)
		(fp_line
			(start -0.7874 0.4064)
			(end -0.7874 -0.4064)
			(stroke
				(width 0.1524)
				(type default)
			)
			(layer "F.SilkS")
		)
		(fp_line
			(start 0.7874 0.4064)
			(end -0.7874 0.4064)
			(stroke
				(width 0.1524)
				(type default)
			)
			(layer "F.SilkS")
		)
		(fp_line
			(start -0.7874 -0.4064)
			(end 0.7874 -0.4064)
			(stroke
				(width 0.1524)
				(type default)
			)
			(layer "F.SilkS")
		)
		(fp_line
			(start 0.7874 -0.4064)
			(end 0.7874 0.4064)
			(stroke
				(width 0.1524)
				(type default)
			)
			(layer "F.SilkS")
		)
		(fp_line
			(start -0.67945 0.3048)
			(end -0.67945 -0.305054)
			(stroke
				(width 0.1)
				(type default)
			)
			(layer "F.Fab")
		)
		(fp_line
			(start -0.12065 0.3048)
			(end -0.67945 0.3048)
			(stroke
				(width 0.1)
				(type default)
			)
			(layer "F.Fab")
		)
		(fp_line
			(start 0.120396 0.3048)
			(end 0.120396 0.2794)
			(stroke
				(width 0.1)
				(type default)
			)
			(layer "F.Fab")
		)
		(fp_line
			(start 0.67945 0.3048)
			(end 0.120396 0.3048)
			(stroke
				(width 0.1)
				(type default)
			)
			(layer "F.Fab")
		)
		(fp_line
			(start -0.12065 0.2794)
			(end -0.12065 0.3048)
			(stroke
				(width 0.1)
				(type default)
			)
			(layer "F.Fab")
		)
		(fp_line
			(start 0.120396 0.2794)
			(end -0.12065 0.2794)
			(stroke
				(width 0.1)
				(type default)
			)
			(layer "F.Fab")
		)
		(fp_line
			(start -0.12065 -0.2794)
			(end 0.12065 -0.2794)
			(stroke
				(width 0.1)
				(type default)
			)
			(layer "F.Fab")
		)
		(fp_line
			(start 0.12065 -0.2794)
			(end 0.12065 -0.3048)
			(stroke
				(width 0.1)
				(type default)
			)
			(layer "F.Fab")
		)
		(fp_line
			(start 0.12065 -0.3048)
			(end 0.67945 -0.3048)
			(stroke
				(width 0.1)
				(type default)
			)
			(layer "F.Fab")
		)
		(fp_line
			(start 0.67945 -0.3048)
			(end 0.67945 0.3048)
			(stroke
				(width 0.1)
				(type default)
			)
			(layer "F.Fab")
		)
		(fp_line
			(start -0.67945 -0.305054)
			(end -0.12065 -0.305054)
			(stroke
				(width 0.1)
				(type default)
			)
			(layer "F.Fab")
		)
		(fp_line
			(start -0.12065 -0.305054)
			(end -0.12065 -0.2794)
			(stroke
				(width 0.1)
				(type default)
			)
			(layer "F.Fab")
		)
		(pad "1" smd circle
			(at -0.40005 0 270)
			(size 0 0)
			(layers "F.Cu" "F.Mask" "F.Paste")
			(net "GND")
		)
		(pad "2" smd circle
			(at 0.40005 0 270)
			(size 0 0)
			(layers "F.Cu" "F.Mask" "F.Paste")
			(net "PD_RST_RTCRST_N")
		)
	)
	(footprint ""
		(layer "F.Cu")
		(at 164.64788 -117.566948)
		(property "Reference" "R1753"
			(at 0 0 0)
			(layer "F.SilkS")
			(hide yes)
			(effects
				(font
					(size 1.27 1.27)
				)
			)
		)
		(property "Value" ""
			(at 0 0 0)
			(layer "F.Fab")
			(effects
				(font
					(size 1.27 1.27)
				)
			)
		)
		(duplicate_pad_numbers_are_jumpers no)
		(fp_line
			(start -0.7874 -0.4064)
			(end 0.7874 -0.4064)
			(stroke
				(width 0.1524)
				(type default)
			)
			(layer "F.SilkS")
		)
		(fp_line
			(start -0.7874 0.4064)
			(end -0.7874 -0.4064)
			(stroke
				(width 0.1524)
				(type default)
			)
			(layer "F.SilkS")
		)
		(fp_line
			(start 0.7874 -0.4064)
			(end 0.7874 0.4064)
			(stroke
				(width 0.1524)
				(type default)
			)
			(layer "F.SilkS")
		)
		(fp_line
			(start 0.7874 0.4064)
			(end -0.7874 0.4064)
			(stroke
				(width 0.1524)
				(type default)
			)
			(layer "F.SilkS")
		)
		(fp_line
			(start -0.67945 -0.305054)
			(end -0.12065 -0.305054)
			(stroke
				(width 0.1)
				(type default)
			)
			(layer "F.Fab")
		)
		(fp_line
			(start -0.67945 0.3048)
			(end -0.67945 -0.305054)
			(stroke
				(width 0.1)
				(type default)
			)
			(layer "F.Fab")
		)
		(fp_line
			(start -0.12065 -0.305054)
			(end -0.12065 -0.2794)
			(stroke
				(width 0.1)
				(type default)
			)
			(layer "F.Fab")
		)
		(fp_line
			(start -0.12065 -0.2794)
			(end 0.12065 -0.2794)
			(stroke
				(width 0.1)
				(type default)
			)
			(layer "F.Fab")
		)
		(fp_line
			(start -0.12065 0.2794)
			(end -0.12065 0.3048)
			(stroke
				(width 0.1)
				(type default)
			)
			(layer "F.Fab")
		)
		(fp_line
			(start -0.12065 0.3048)
			(end -0.67945 0.3048)
			(stroke
				(width 0.1)
				(type default)
			)
			(layer "F.Fab")
		)
		(fp_line
			(start 0.120396 0.2794)
			(end -0.12065 0.2794)
			(stroke
				(width 0.1)
				(type default)
			)
			(layer "F.Fab")
		)
		(fp_line
			(start 0.120396 0.3048)
			(end 0.120396 0.2794)
			(stroke
				(width 0.1)
				(type default)
			)
			(layer "F.Fab")
		)
		(fp_line
			(start 0.12065 -0.3048)
			(end 0.67945 -0.3048)
			(stroke
				(width 0.1)
				(type default)
			)
			(layer "F.Fab")
		)
		(fp_line
			(start 0.12065 -0.2794)
			(end 0.12065 -0.3048)
			(stroke
				(width 0.1)
				(type default)
			)
			(layer "F.Fab")
		)
		(fp_line
			(start 0.67945 -0.3048)
			(end 0.67945 0.3048)
			(stroke
				(width 0.1)
				(type default)
			)
			(layer "F.Fab")
		)
		(fp_line
			(start 0.67945 0.3048)
			(end 0.120396 0.3048)
			(stroke
				(width 0.1)
				(type default)
			)
			(layer "F.Fab")
		)
		(pad "1" smd circle
			(at -0.40005 0)
			(size 0 0)
			(layers "F.Cu" "F.Mask" "F.Paste")
			(net "SGPIO_DI_0")
		)
		(pad "2" smd circle
			(at 0.40005 0)
			(size 0 0)
			(layers "F.Cu" "F.Mask" "F.Paste")
			(net "SGPIO_DEBUG_PLD_DIN")
		)
	)
	(footprint ""
		(layer "F.Cu")
		(at 27.628596 -397.406876)
		(property "Reference" "R3279"
			(at 0 0 0)
			(layer "F.SilkS")
			(hide yes)
			(effects
				(font
					(size 1.27 1.27)
				)
			)
		)
		(property "Value" ""
			(at 0 0 0)
			(layer "F.Fab")
			(effects
				(font
					(size 1.27 1.27)
				)
			)
		)
		(duplicate_pad_numbers_are_jumpers no)
		(fp_line
			(start -0.7874 -0.4064)
			(end 0.7874 -0.4064)
			(stroke
				(width 0.1524)
				(type default)
			)
			(layer "F.SilkS")
		)
		(fp_line
			(start -0.7874 0.4064)
			(end -0.7874 -0.4064)
			(stroke
				(width 0.1524)
				(type default)
			)
			(layer "F.SilkS")
		)
		(fp_line
			(start 0.7874 -0.4064)
			(end 0.7874 0.4064)
			(stroke
				(width 0.1524)
				(type default)
			)
			(layer "F.SilkS")
		)
		(fp_line
			(start 0.7874 0.4064)
			(end -0.7874 0.4064)
			(stroke
				(width 0.1524)
				(type default)
			)
			(layer "F.SilkS")
		)
		(fp_line
			(start -0.67945 -0.305054)
			(end -0.12065 -0.305054)
			(stroke
				(width 0.1)
				(type default)
			)
			(layer "F.Fab")
		)
		(fp_line
			(start -0.67945 0.3048)
			(end -0.67945 -0.305054)
			(stroke
				(width 0.1)
				(type default)
			)
			(layer "F.Fab")
		)
		(fp_line
			(start -0.12065 -0.305054)
			(end -0.12065 -0.2794)
			(stroke
				(width 0.1)
				(type default)
			)
			(layer "F.Fab")
		)
		(fp_line
			(start -0.12065 -0.2794)
			(end 0.12065 -0.2794)
			(stroke
				(width 0.1)
				(type default)
			)
			(layer "F.Fab")
		)
		(fp_line
			(start -0.12065 0.2794)
			(end -0.12065 0.3048)
			(stroke
				(width 0.1)
				(type default)
			)
			(layer "F.Fab")
		)
		(fp_line
			(start -0.12065 0.3048)
			(end -0.67945 0.3048)
			(stroke
				(width 0.1)
				(type default)
			)
			(layer "F.Fab")
		)
		(fp_line
			(start 0.120396 0.2794)
			(end -0.12065 0.2794)
			(stroke
				(width 0.1)
				(type default)
			)
			(layer "F.Fab")
		)
		(fp_line
			(start 0.120396 0.3048)
			(end 0.120396 0.2794)
			(stroke
				(width 0.1)
				(type default)
			)
			(layer "F.Fab")
		)
		(fp_line
			(start 0.12065 -0.3048)
			(end 0.67945 -0.3048)
			(stroke
				(width 0.1)
				(type default)
			)
			(layer "F.Fab")
		)
		(fp_line
			(start 0.12065 -0.2794)
			(end 0.12065 -0.3048)
			(stroke
				(width 0.1)
				(type default)
			)
			(layer "F.Fab")
		)
		(fp_line
			(start 0.67945 -0.3048)
			(end 0.67945 0.3048)
			(stroke
				(width 0.1)
				(type default)
			)
			(layer "F.Fab")
		)
		(fp_line
			(start 0.67945 0.3048)
			(end 0.120396 0.3048)
			(stroke
				(width 0.1)
				(type default)
			)
			(layer "F.Fab")
		)
		(pad "1" smd circle
			(at -0.40005 0)
			(size 0 0)
			(layers "F.Cu" "F.Mask" "F.Paste")
			(net "FM_P2E_EQB1")
		)
		(pad "2" smd circle
			(at 0.40005 0)
			(size 0 0)
			(layers "F.Cu" "F.Mask" "F.Paste")
			(net "GND")
		)
	)
	(footprint ""
		(layer "F.Cu")
		(at 398.96669 -402.371052 -90)
		(property "Reference" "C953"
			(at 0 0 270)
			(layer "F.SilkS")
			(hide yes)
			(effects
				(font
					(size 1.27 1.27)
				)
			)
		)
		(property "Value" ""
			(at 0 0 270)
			(layer "F.Fab")
			(effects
				(font
					(size 1.27 1.27)
				)
			)
		)
		(duplicate_pad_numbers_are_jumpers no)
		(fp_line
			(start -0.299974 0.150114)
			(end -0.299974 -0.150114)
			(stroke
				(width 0.1)
				(type default)
			)
			(layer "F.Fab")
		)
		(fp_line
			(start 0.299974 0.150114)
			(end -0.299974 0.150114)
			(stroke
				(width 0.1)
				(type default)
			)
			(layer "F.Fab")
		)
		(fp_line
			(start -0.299974 -0.150114)
			(end 0.299974 -0.150114)
			(stroke
				(width 0.1)
				(type default)
			)
			(layer "F.Fab")
		)
		(fp_line
			(start 0.299974 -0.150114)
			(end 0.299974 0.150114)
			(stroke
				(width 0.1)
				(type default)
			)
			(layer "F.Fab")
		)
		(pad "1" smd rect
			(at -0.2667 0 270)
			(size 0.3048 0.381)
			(layers "F.Cu" "F.Mask" "F.Paste")
			(net "P5E_CPU0_PE2_TX_C_DP<6>")
		)
		(pad "2" smd rect
			(at 0.2667 0 270)
			(size 0.3048 0.381)
			(layers "F.Cu" "F.Mask" "F.Paste")
			(net "P5E_CPU0_PE2_TX_DP<6>")
		)
	)
	(footprint ""
		(layer "F.Cu")
		(at 51.593496 -109.53877)
		(property "Reference" "R3728"
			(at 0 0 0)
			(layer "F.SilkS")
			(hide yes)
			(effects
				(font
					(size 1.27 1.27)
				)
			)
		)
		(property "Value" ""
			(at 0 0 0)
			(layer "F.Fab")
			(effects
				(font
					(size 1.27 1.27)
				)
			)
		)
		(duplicate_pad_numbers_are_jumpers no)
		(fp_line
			(start -0.7874 -0.4064)
			(end 0.7874 -0.4064)
			(stroke
				(width 0.1524)
				(type default)
			)
			(layer "F.SilkS")
		)
		(fp_line
			(start -0.7874 0.4064)
			(end -0.7874 -0.4064)
			(stroke
				(width 0.1524)
				(type default)
			)
			(layer "F.SilkS")
		)
		(fp_line
			(start 0.7874 -0.4064)
			(end 0.7874 0.4064)
			(stroke
				(width 0.1524)
				(type default)
			)
			(layer "F.SilkS")
		)
		(fp_line
			(start 0.7874 0.4064)
			(end -0.7874 0.4064)
			(stroke
				(width 0.1524)
				(type default)
			)
			(layer "F.SilkS")
		)
		(fp_line
			(start -0.67945 -0.305054)
			(end -0.12065 -0.305054)
			(stroke
				(width 0.1)
				(type default)
			)
			(layer "F.Fab")
		)
		(fp_line
			(start -0.67945 0.3048)
			(end -0.67945 -0.305054)
			(stroke
				(width 0.1)
				(type default)
			)
			(layer "F.Fab")
		)
		(fp_line
			(start -0.12065 -0.305054)
			(end -0.12065 -0.2794)
			(stroke
				(width 0.1)
				(type default)
			)
			(layer "F.Fab")
		)
		(fp_line
			(start -0.12065 -0.2794)
			(end 0.12065 -0.2794)
			(stroke
				(width 0.1)
				(type default)
			)
			(layer "F.Fab")
		)
		(fp_line
			(start -0.12065 0.2794)
			(end -0.12065 0.3048)
			(stroke
				(width 0.1)
				(type default)
			)
			(layer "F.Fab")
		)
		(fp_line
			(start -0.12065 0.3048)
			(end -0.67945 0.3048)
			(stroke
				(width 0.1)
				(type default)
			)
			(layer "F.Fab")
		)
		(fp_line
			(start 0.120396 0.2794)
			(end -0.12065 0.2794)
			(stroke
				(width 0.1)
				(type default)
			)
			(layer "F.Fab")
		)
		(fp_line
			(start 0.120396 0.3048)
			(end 0.120396 0.2794)
			(stroke
				(width 0.1)
				(type default)
			)
			(layer "F.Fab")
		)
		(fp_line
			(start 0.12065 -0.3048)
			(end 0.67945 -0.3048)
			(stroke
				(width 0.1)
				(type default)
			)
			(layer "F.Fab")
		)
		(fp_line
			(start 0.12065 -0.2794)
			(end 0.12065 -0.3048)
			(stroke
				(width 0.1)
				(type default)
			)
			(layer "F.Fab")
		)
		(fp_line
			(start 0.67945 -0.3048)
			(end 0.67945 0.3048)
			(stroke
				(width 0.1)
				(type default)
			)
			(layer "F.Fab")
		)
		(fp_line
			(start 0.67945 0.3048)
			(end 0.120396 0.3048)
			(stroke
				(width 0.1)
				(type default)
			)
			(layer "F.Fab")
		)
		(pad "1" smd circle
			(at -0.40005 0)
			(size 0 0)
			(layers "F.Cu" "F.Mask" "F.Paste")
			(net "P3V3_AUX")
		)
		(pad "2" smd circle
			(at 0.40005 0)
			(size 0 0)
			(layers "F.Cu" "F.Mask" "F.Paste")
			(net "SMB_LM75_1_3V3AUX_SDA")
		)
	)
	(footprint ""
		(layer "F.Cu")
		(at 237.401608 -401.673822)
		(property "Reference" "PR3994"
			(at 0 0 0)
			(layer "F.SilkS")
			(hide yes)
			(effects
				(font
					(size 1.27 1.27)
				)
			)
		)
		(property "Value" ""
			(at 0 0 0)
			(layer "F.Fab")
			(effects
				(font
					(size 1.27 1.27)
				)
			)
		)
		(duplicate_pad_numbers_are_jumpers no)
		(fp_line
			(start -0.7874 -0.4064)
			(end 0.7874 -0.4064)
			(stroke
				(width 0.1524)
				(type default)
			)
			(layer "F.SilkS")
		)
		(fp_line
			(start -0.7874 0.4064)
			(end -0.7874 -0.4064)
			(stroke
				(width 0.1524)
				(type default)
			)
			(layer "F.SilkS")
		)
		(fp_line
			(start 0.7874 -0.4064)
			(end 0.7874 0.4064)
			(stroke
				(width 0.1524)
				(type default)
			)
			(layer "F.SilkS")
		)
		(fp_line
			(start 0.7874 0.4064)
			(end -0.7874 0.4064)
			(stroke
				(width 0.1524)
				(type default)
			)
			(layer "F.SilkS")
		)
		(fp_line
			(start -0.67945 -0.305054)
			(end -0.12065 -0.305054)
			(stroke
				(width 0.1)
				(type default)
			)
			(layer "F.Fab")
		)
		(fp_line
			(start -0.67945 0.3048)
			(end -0.67945 -0.305054)
			(stroke
				(width 0.1)
				(type default)
			)
			(layer "F.Fab")
		)
		(fp_line
			(start -0.12065 -0.305054)
			(end -0.12065 -0.2794)
			(stroke
				(width 0.1)
				(type default)
			)
			(layer "F.Fab")
		)
		(fp_line
			(start -0.12065 -0.2794)
			(end 0.12065 -0.2794)
			(stroke
				(width 0.1)
				(type default)
			)
			(layer "F.Fab")
		)
		(fp_line
			(start -0.12065 0.2794)
			(end -0.12065 0.3048)
			(stroke
				(width 0.1)
				(type default)
			)
			(layer "F.Fab")
		)
		(fp_line
			(start -0.12065 0.3048)
			(end -0.67945 0.3048)
			(stroke
				(width 0.1)
				(type default)
			)
			(layer "F.Fab")
		)
		(fp_line
			(start 0.120396 0.2794)
			(end -0.12065 0.2794)
			(stroke
				(width 0.1)
				(type default)
			)
			(layer "F.Fab")
		)
		(fp_line
			(start 0.120396 0.3048)
			(end 0.120396 0.2794)
			(stroke
				(width 0.1)
				(type default)
			)
			(layer "F.Fab")
		)
		(fp_line
			(start 0.12065 -0.3048)
			(end 0.67945 -0.3048)
			(stroke
				(width 0.1)
				(type default)
			)
			(layer "F.Fab")
		)
		(fp_line
			(start 0.12065 -0.2794)
			(end 0.12065 -0.3048)
			(stroke
				(width 0.1)
				(type default)
			)
			(layer "F.Fab")
		)
		(fp_line
			(start 0.67945 -0.3048)
			(end 0.67945 0.3048)
			(stroke
				(width 0.1)
				(type default)
			)
			(layer "F.Fab")
		)
		(fp_line
			(start 0.67945 0.3048)
			(end 0.120396 0.3048)
			(stroke
				(width 0.1)
				(type default)
			)
			(layer "F.Fab")
		)
		(pad "1" smd circle
			(at -0.40005 0)
			(size 0 0)
			(layers "F.Cu" "F.Mask" "F.Paste")
			(net "HSC_D_OC_4")
		)
		(pad "2" smd circle
			(at 0.40005 0)
			(size 0 0)
			(layers "F.Cu" "F.Mask" "F.Paste")
			(net "HSC_D_OC_R")
		)
	)
)
